# BASEBOARD_FAB2 (Tioga Pass) — schematic netlist excerpt (pin names and nets, part order shuffled) for the footprints in the layout excerpt that follows; sources: Cadence DE-HDL packaged netlist, KiCad conversion of Wiwynn_Tioga_Pass_MB.brd

R25W152  RES  4.75K 1% CHIP  pkg 0402  page 150 : A = GND ; B = TP_RGMII2TXD2_GPIOU2
C4U4  CAP  10UF 4V 20% X6S  pkg 0603LF  page 231 : A = PVPP_ABC ; B = GND
R6P5  RES  42.2 1.0% EMPTY  pkg 0402  page 103 : A = CLK_100M_CPU1_BCLK0_DP ; B = GND

(kicad_pcb
	(version 20260206)
	(generator "pcbnew")
	(generator_version "10.0")
	(general
		(thickness 1.6)
		(legacy_teardrops no)
	)
	(paper "A4")
	(title_block
		(title "Wiwynn_Tioga_Pass_MB.brd")
		(comment 1 "Tioga Pass / footprints 2963-2965 of 4770")
	)
	(layers
		(0 "F.Cu" signal "TOP")
		(4 "In1.Cu" signal "L2GND")
		(6 "In2.Cu" signal "L3")
		(8 "In3.Cu" signal "L4GND")
		(10 "In4.Cu" signal "L5")
		(12 "In5.Cu" signal "L6GND")
		(14 "In6.Cu" signal "L7VCC")
		(16 "In7.Cu" signal "L8VCC")
		(18 "In8.Cu" signal "L9GND")
		(20 "In9.Cu" signal "L10")
		(22 "In10.Cu" signal "L11GND")
		(24 "In11.Cu" signal "L12")
		(26 "In12.Cu" signal "L13GND")
		(2 "B.Cu" signal "BOTTOM")
		(9 "F.Adhes" user "F.Adhesive")
		(11 "B.Adhes" user "B.Adhesive")
		(13 "F.Paste" user "Package Geometry/Pastemask Top")
		(15 "B.Paste" user "Package Geometry/Pastemask Bottom")
		(5 "F.SilkS" user "Ref Des/Silkscreen Top")
		(7 "B.SilkS" user "Ref Des/Silkscreen Bottom")
		(1 "F.Mask" user "Board Geometry/Soldermask Top")
		(3 "B.Mask" user "Board Geometry/Soldermask Bottom")
		(17 "Dwgs.User" user "User.Drawings")
		(19 "Cmts.User" user "User.Comments")
		(21 "Eco1.User" user "User.Eco1")
		(23 "Eco2.User" user "User.Eco2")
		(25 "Edge.Cuts" user "Board Geometry/Outline")
		(27 "Margin" user)
		(31 "F.CrtYd" user "Package Geometry/Place Bound Top")
		(29 "B.CrtYd" user "Package Geometry/Place Bound Bottom")
		(35 "F.Fab" user "Ref Des/Assembly Top")
		(33 "B.Fab" user "Ref Des/Assembly Bottom")
	)
	(footprint ""
		(layer "B.Cu")
		(at 406.7556 -29.6164)
		(property "Reference" "R25W152"
			(at 0.8382 -0.67818 0)
			(unlocked yes)
			(layer "B.SilkS")
			(effects
				(font
					(size 0.4064 0.254)
					(thickness 0.1524)
				)
				(justify left mirror)
			)
		)
		(property "Value" ""
			(at 0 0 0)
			(layer "B.Fab")
			(effects
				(font
					(size 1.27 1.27)
				)
				(justify mirror)
			)
		)
		(duplicate_pad_numbers_are_jumpers no)
		(fp_poly
			(pts
				(xy 0.2794 -0.1016) (xy -0.2794 -0.1016) (xy -0.2794 0.9906) (xy 0.2794 0.9906)
			)
			(stroke
				(width 0)
				(type default)
			)
			(fill no)
			(layer "B.CrtYd")
		)
		(fp_line
			(start -0.2794 -0.1016)
			(end 0.2794 -0.1016)
			(stroke
				(width 0.1)
				(type default)
			)
			(layer "B.Fab")
		)
		(fp_line
			(start -0.2794 0.9906)
			(end -0.2794 -0.1016)
			(stroke
				(width 0.1)
				(type default)
			)
			(layer "B.Fab")
		)
		(fp_line
			(start 0.2794 -0.1016)
			(end 0.2794 0.9906)
			(stroke
				(width 0.1)
				(type default)
			)
			(layer "B.Fab")
		)
		(fp_line
			(start 0.2794 0.9906)
			(end -0.2794 0.9906)
			(stroke
				(width 0.1)
				(type default)
			)
			(layer "B.Fab")
		)
		(pad "1" smd rect
			(at 0 0 180)
			(size 0.508 0.508)
			(layers "B.Cu" "B.Mask" "B.Paste")
			(net "GND")
		)
		(pad "2" smd rect
			(at 0 0.889 180)
			(size 0.508 0.508)
			(layers "B.Cu" "B.Mask" "B.Paste")
			(net "TP_RGMII2TXD2_GPIOU2")
		)
		(zone
			(layer "B.Cu")
			(hatch none 0.5)
			(connect_pads
				(clearance 0)
			)
			(min_thickness 0.25)
			(keepout
				(tracks allowed)
				(vias not_allowed)
				(pads allowed)
				(copperpour not_allowed)
				(footprints allowed)
			)
			(placement
				(enabled no)
				(sheetname "")
			)
			(fill
				(thermal_gap 0.5)
				(thermal_bridge_width 0.5)
				(island_removal_mode 0)
			)
			(polygon
				(pts
					(xy 407.0096 -29.3624) (xy 406.5016 -29.3624) (xy 406.5016 -28.9814) (xy 407.0096 -28.9814)
				)
			)
		)
		(zone
			(layer "B.Cu")
			(hatch none 0.5)
			(connect_pads
				(clearance 0)
			)
			(min_thickness 0.25)
			(keepout
				(tracks not_allowed)
				(vias allowed)
				(pads allowed)
				(copperpour not_allowed)
				(footprints allowed)
			)
			(placement
				(enabled no)
				(sheetname "")
			)
			(fill
				(thermal_gap 0.5)
				(thermal_bridge_width 0.5)
				(island_removal_mode 0)
			)
			(polygon
				(pts
					(xy 407.0096 -28.9814) (xy 406.5016 -28.9814) (xy 406.5016 -29.3624) (xy 407.0096 -29.3624)
				)
			)
		)
	)
	(footprint ""
		(layer "B.Cu")
		(at 318.797432 1.7018 -90)
		(property "Reference" "C4U4"
			(at 0 0 90)
			(layer "B.SilkS")
			(hide yes)
			(effects
				(font
					(size 1.27 1.27)
				)
				(justify mirror)
			)
		)
		(property "Value" ""
			(at 0 0 90)
			(layer "B.Fab")
			(effects
				(font
					(size 1.27 1.27)
				)
				(justify mirror)
			)
		)
		(duplicate_pad_numbers_are_jumpers no)
		(fp_poly
			(pts
				(xy 0.4953 -0.2032) (xy -0.4953 -0.2032) (xy -0.4953 1.6002) (xy 0.4953 1.6002)
			)
			(stroke
				(width 0)
				(type default)
			)
			(fill no)
			(layer "B.CrtYd")
		)
		(fp_line
			(start -0.4953 1.6002)
			(end 0.4953 1.6002)
			(stroke
				(width 0.1)
				(type default)
			)
			(layer "B.Fab")
		)
		(fp_line
			(start 0.4953 1.6002)
			(end 0.4953 -0.2032)
			(stroke
				(width 0.1)
				(type default)
			)
			(layer "B.Fab")
		)
		(fp_line
			(start -0.4953 -0.2032)
			(end -0.4953 1.6002)
			(stroke
				(width 0.1)
				(type default)
			)
			(layer "B.Fab")
		)
		(fp_line
			(start 0.4953 -0.2032)
			(end -0.4953 -0.2032)
			(stroke
				(width 0.1)
				(type default)
			)
			(layer "B.Fab")
		)
		(pad "1" smd rect
			(at 0 0 90)
			(size 0.762 0.889)
			(layers "B.Cu" "B.Mask" "B.Paste")
			(net "PVPP_ABC")
		)
		(pad "2" smd rect
			(at 0 1.397 90)
			(size 0.762 0.889)
			(layers "B.Cu" "B.Mask" "B.Paste")
			(net "GND")
		)
		(zone
			(layer "B.Cu")
			(hatch none 0.5)
			(connect_pads
				(clearance 0)
			)
			(min_thickness 0.25)
			(keepout
				(tracks not_allowed)
				(vias allowed)
				(pads allowed)
				(copperpour not_allowed)
				(footprints allowed)
			)
			(placement
				(enabled no)
				(sheetname "")
			)
			(fill
				(thermal_gap 0.5)
				(thermal_bridge_width 0.5)
				(island_removal_mode 0)
			)
			(polygon
				(pts
					(xy 318.352932 2.0828) (xy 318.352932 1.3208) (xy 317.844932 1.3208) (xy 317.844932 2.0828)
				)
			)
		)
	)
	(footprint ""
		(layer "B.Cu")
		(at 168.656 -87.757)
		(property "Reference" "R6P5"
			(at 0 0 0)
			(layer "B.SilkS")
			(hide yes)
			(effects
				(font
					(size 1.27 1.27)
				)
				(justify mirror)
			)
		)
		(property "Value" ""
			(at 0 0 0)
			(layer "B.Fab")
			(effects
				(font
					(size 1.27 1.27)
				)
				(justify mirror)
			)
		)
		(duplicate_pad_numbers_are_jumpers no)
		(fp_poly
			(pts
				(xy 0.2794 -0.1016) (xy -0.2794 -0.1016) (xy -0.2794 0.9906) (xy 0.2794 0.9906)
			)
			(stroke
				(width 0)
				(type default)
			)
			(fill no)
			(layer "B.CrtYd")
		)
		(fp_line
			(start -0.2794 -0.1016)
			(end 0.2794 -0.1016)
			(stroke
				(width 0.1)
				(type default)
			)
			(layer "B.Fab")
		)
		(fp_line
			(start -0.2794 0.9906)
			(end -0.2794 -0.1016)
			(stroke
				(width 0.1)
				(type default)
			)
			(layer "B.Fab")
		)
		(fp_line
			(start 0.2794 -0.1016)
			(end 0.2794 0.9906)
			(stroke
				(width 0.1)
				(type default)
			)
			(layer "B.Fab")
		)
		(fp_line
			(start 0.2794 0.9906)
			(end -0.2794 0.9906)
			(stroke
				(width 0.1)
				(type default)
			)
			(layer "B.Fab")
		)
		(pad "1" smd rect
			(at 0 0 180)
			(size 0.508 0.508)
			(layers "B.Cu" "B.Mask" "B.Paste")
			(net "CLK_100M_CPU1_BCLK0_DP")
		)
		(pad "2" smd rect
			(at 0 0.889 180)
			(size 0.508 0.508)
			(layers "B.Cu" "B.Mask" "B.Paste")
			(net "GND")
		)
		(zone
			(layer "B.Cu")
			(hatch none 0.5)
			(connect_pads
				(clearance 0)
			)
			(min_thickness 0.25)
			(keepout
				(tracks allowed)
				(vias not_allowed)
				(pads allowed)
				(copperpour not_allowed)
				(footprints allowed)
			)
			(placement
				(enabled no)
				(sheetname "")
			)
			(fill
				(thermal_gap 0.5)
				(thermal_bridge_width 0.5)
				(island_removal_mode 0)
			)
			(polygon
				(pts
					(xy 168.91 -87.503) (xy 168.402 -87.503) (xy 168.402 -87.122) (xy 168.91 -87.122)
				)
			)
		)
		(zone
			(layer "B.Cu")
			(hatch none 0.5)
			(connect_pads
				(clearance 0)
			)
			(min_thickness 0.25)
			(keepout
				(tracks not_allowed)
				(vias allowed)
				(pads allowed)
				(copperpour not_allowed)
				(footprints allowed)
			)
			(placement
				(enabled no)
				(sheetname "")
			)
			(fill
				(thermal_gap 0.5)
				(thermal_bridge_width 0.5)
				(island_removal_mode 0)
			)
			(polygon
				(pts
					(xy 168.91 -87.122) (xy 168.402 -87.122) (xy 168.402 -87.503) (xy 168.91 -87.503)
				)
			)
		)
	)
)
